# T6G (Grand Teton) — schematic netlist excerpt (pin names and nets, part order shuffled) for the footprints in the layout excerpt that follows; sources: Cadence DE-HDL packaged netlist, KiCad conversion of 04192023_DAF0TMB3IC0_F0TG_MB_C_brd_V02_OCP.brd

R525  Q_RES  1K 1% CHIP  pkg 0402LF  page 54 : A = PVDD18_S5_P1 ; B = JTAG_CPU1_TRST_N
C6666  Q_CAP_DIFFBUS  DIFF BUS_0.22UF 6.3V 20% X6S  pkg C0201  page 330 : \1\ = P5E_CPU1_P1_TX_BUF_C_DN<2> ; \2\ = P5E_CPU1_P1_TX_BUF_DN<2>
R1460  Q_RES  2.2K 5% EMPTY  pkg 0402LF  page 151 : A = I3C_BMC_SWB_SDA ; B = P3V3_AUX

(kicad_pcb
	(version 20260206)
	(generator "pcbnew")
	(generator_version "10.0")
	(general
		(thickness 1.6)
		(legacy_teardrops no)
	)
	(paper "A4")
	(title_block
		(title "04192023_DAF0TMB3IC0_F0TG_MB_C_brd_V02_OCP.brd")
		(comment 1 "Grand Teton / footprints 8311-8313 of 8354")
	)
	(layers
		(0 "F.Cu" signal "TOP")
		(4 "In1.Cu" signal "GND")
		(6 "In2.Cu" signal "IN1")
		(8 "In3.Cu" signal "GND1")
		(10 "In4.Cu" signal "IN2")
		(12 "In5.Cu" signal "GND2")
		(14 "In6.Cu" signal "IN3")
		(16 "In7.Cu" signal "GND3")
		(18 "In8.Cu" signal "VCC")
		(20 "In9.Cu" signal "VCC1")
		(22 "In10.Cu" signal "GND4")
		(24 "In11.Cu" signal "IN4")
		(26 "In12.Cu" signal "GND5")
		(28 "In13.Cu" signal "IN5")
		(30 "In14.Cu" signal "GND6")
		(32 "In15.Cu" signal "IN6")
		(34 "In16.Cu" signal "GND7")
		(2 "B.Cu" signal "BOTTOM")
		(9 "F.Adhes" user "F.Adhesive")
		(11 "B.Adhes" user "B.Adhesive")
		(13 "F.Paste" user "Package Geometry/Pastemask Top")
		(15 "B.Paste" user "Package Geometry/Pastemask Bottom")
		(5 "F.SilkS" user "Ref Des/Silkscreen Top")
		(7 "B.SilkS" user "Ref Des/Silkscreen Bottom")
		(1 "F.Mask" user "Board Geometry/Soldermask Top")
		(3 "B.Mask" user "Board Geometry/Soldermask Bottom")
		(17 "Dwgs.User" user "User.Drawings")
		(19 "Cmts.User" user "User.Comments")
		(21 "Eco1.User" user "User.Eco1")
		(23 "Eco2.User" user "User.Eco2")
		(25 "Edge.Cuts" user "Board Geometry/Outline")
		(27 "Margin" user)
		(31 "F.CrtYd" user "Package Geometry/Place Bound Top")
		(29 "B.CrtYd" user "Package Geometry/Place Bound Bottom")
		(35 "F.Fab" user "Ref Des/Assembly Top")
		(33 "B.Fab" user "Ref Des/Assembly Bottom")
	)
	(footprint ""
		(layer "B.Cu")
		(at 173.301914 -13.416788 -90)
		(property "Reference" "R1460"
			(at 0 0 90)
			(layer "B.SilkS")
			(hide yes)
			(effects
				(font
					(size 1.27 1.27)
				)
				(justify mirror)
			)
		)
		(property "Value" ""
			(at 0 0 90)
			(layer "B.Fab")
			(effects
				(font
					(size 1.27 1.27)
				)
				(justify mirror)
			)
		)
		(duplicate_pad_numbers_are_jumpers no)
		(fp_line
			(start -0.7874 0.4064)
			(end 0.7874 0.4064)
			(stroke
				(width 0.1524)
				(type default)
			)
			(layer "B.SilkS")
		)
		(fp_line
			(start 0.7874 0.4064)
			(end 0.7874 -0.4064)
			(stroke
				(width 0.1524)
				(type default)
			)
			(layer "B.SilkS")
		)
		(fp_line
			(start -0.7874 -0.4064)
			(end -0.7874 0.4064)
			(stroke
				(width 0.1524)
				(type default)
			)
			(layer "B.SilkS")
		)
		(fp_line
			(start 0.7874 -0.4064)
			(end -0.7874 -0.4064)
			(stroke
				(width 0.1524)
				(type default)
			)
			(layer "B.SilkS")
		)
		(fp_line
			(start -0.67945 0.3048)
			(end -0.120396 0.3048)
			(stroke
				(width 0.1)
				(type default)
			)
			(layer "B.Fab")
		)
		(fp_line
			(start -0.120396 0.3048)
			(end -0.120396 0.2794)
			(stroke
				(width 0.1)
				(type default)
			)
			(layer "B.Fab")
		)
		(fp_line
			(start 0.12065 0.3048)
			(end 0.67945 0.3048)
			(stroke
				(width 0.1)
				(type default)
			)
			(layer "B.Fab")
		)
		(fp_line
			(start 0.67945 0.3048)
			(end 0.67945 -0.305054)
			(stroke
				(width 0.1)
				(type default)
			)
			(layer "B.Fab")
		)
		(fp_line
			(start -0.120396 0.2794)
			(end 0.12065 0.2794)
			(stroke
				(width 0.1)
				(type default)
			)
			(layer "B.Fab")
		)
		(fp_line
			(start 0.12065 0.2794)
			(end 0.12065 0.3048)
			(stroke
				(width 0.1)
				(type default)
			)
			(layer "B.Fab")
		)
		(fp_line
			(start -0.12065 -0.2794)
			(end -0.12065 -0.3048)
			(stroke
				(width 0.1)
				(type default)
			)
			(layer "B.Fab")
		)
		(fp_line
			(start 0.12065 -0.2794)
			(end -0.12065 -0.2794)
			(stroke
				(width 0.1)
				(type default)
			)
			(layer "B.Fab")
		)
		(fp_line
			(start -0.67945 -0.3048)
			(end -0.67945 0.3048)
			(stroke
				(width 0.1)
				(type default)
			)
			(layer "B.Fab")
		)
		(fp_line
			(start -0.12065 -0.3048)
			(end -0.67945 -0.3048)
			(stroke
				(width 0.1)
				(type default)
			)
			(layer "B.Fab")
		)
		(fp_line
			(start 0.12065 -0.305054)
			(end 0.12065 -0.2794)
			(stroke
				(width 0.1)
				(type default)
			)
			(layer "B.Fab")
		)
		(fp_line
			(start 0.67945 -0.305054)
			(end 0.12065 -0.305054)
			(stroke
				(width 0.1)
				(type default)
			)
			(layer "B.Fab")
		)
		(pad "1" smd circle
			(at 0.40005 0 90)
			(size 0 0)
			(layers "B.Cu" "B.Mask" "B.Paste")
			(net "I3C_BMC_SWB_SDA")
		)
		(pad "2" smd circle
			(at -0.40005 0 90)
			(size 0 0)
			(layers "B.Cu" "B.Mask" "B.Paste")
			(net "P3V3_AUX")
		)
	)
	(footprint ""
		(layer "B.Cu")
		(at 55.426864 -408.517344 90)
		(property "Reference" "C6666"
			(at 0 0 90)
			(layer "B.SilkS")
			(hide yes)
			(effects
				(font
					(size 1.27 1.27)
				)
				(justify mirror)
			)
		)
		(property "Value" ""
			(at 0 0 90)
			(layer "B.Fab")
			(effects
				(font
					(size 1.27 1.27)
				)
				(justify mirror)
			)
		)
		(duplicate_pad_numbers_are_jumpers no)
		(fp_line
			(start 0.299974 -0.150114)
			(end -0.299974 -0.150114)
			(stroke
				(width 0.1)
				(type default)
			)
			(layer "B.Fab")
		)
		(fp_line
			(start -0.299974 -0.150114)
			(end -0.299974 0.150114)
			(stroke
				(width 0.1)
				(type default)
			)
			(layer "B.Fab")
		)
		(fp_line
			(start 0.299974 0.150114)
			(end 0.299974 -0.150114)
			(stroke
				(width 0.1)
				(type default)
			)
			(layer "B.Fab")
		)
		(fp_line
			(start -0.299974 0.150114)
			(end 0.299974 0.150114)
			(stroke
				(width 0.1)
				(type default)
			)
			(layer "B.Fab")
		)
		(pad "1" smd rect
			(at 0.2667 0 270)
			(size 0.3048 0.381)
			(layers "B.Cu" "B.Mask" "B.Paste")
			(net "P5E_CPU1_P1_TX_BUF_C_DN<2>")
		)
		(pad "2" smd rect
			(at -0.2667 0 270)
			(size 0.3048 0.381)
			(layers "B.Cu" "B.Mask" "B.Paste")
			(net "P5E_CPU1_P1_TX_BUF_DN<2>")
		)
	)
	(footprint ""
		(layer "B.Cu")
		(at 150.259034 -201.977752 90)
		(property "Reference" "R525"
			(at 0 0 90)
			(layer "B.SilkS")
			(hide yes)
			(effects
				(font
					(size 1.27 1.27)
				)
				(justify mirror)
			)
		)
		(property "Value" ""
			(at 0 0 90)
			(layer "B.Fab")
			(effects
				(font
					(size 1.27 1.27)
				)
				(justify mirror)
			)
		)
		(duplicate_pad_numbers_are_jumpers no)
		(fp_line
			(start 0.7874 -0.4064)
			(end -0.7874 -0.4064)
			(stroke
				(width 0.1524)
				(type default)
			)
			(layer "B.SilkS")
		)
		(fp_line
			(start -0.7874 -0.4064)
			(end -0.7874 0.4064)
			(stroke
				(width 0.1524)
				(type default)
			)
			(layer "B.SilkS")
		)
		(fp_line
			(start 0.7874 0.4064)
			(end 0.7874 -0.4064)
			(stroke
				(width 0.1524)
				(type default)
			)
			(layer "B.SilkS")
		)
		(fp_line
			(start -0.7874 0.4064)
			(end 0.7874 0.4064)
			(stroke
				(width 0.1524)
				(type default)
			)
			(layer "B.SilkS")
		)
		(fp_line
			(start 0.67945 -0.305054)
			(end 0.12065 -0.305054)
			(stroke
				(width 0.1)
				(type default)
			)
			(layer "B.Fab")
		)
		(fp_line
			(start 0.12065 -0.305054)
			(end 0.12065 -0.2794)
			(stroke
				(width 0.1)
				(type default)
			)
			(layer "B.Fab")
		)
		(fp_line
			(start -0.12065 -0.3048)
			(end -0.67945 -0.3048)
			(stroke
				(width 0.1)
				(type default)
			)
			(layer "B.Fab")
		)
		(fp_line
			(start -0.67945 -0.3048)
			(end -0.67945 0.3048)
			(stroke
				(width 0.1)
				(type default)
			)
			(layer "B.Fab")
		)
		(fp_line
			(start 0.12065 -0.2794)
			(end -0.12065 -0.2794)
			(stroke
				(width 0.1)
				(type default)
			)
			(layer "B.Fab")
		)
		(fp_line
			(start -0.12065 -0.2794)
			(end -0.12065 -0.3048)
			(stroke
				(width 0.1)
				(type default)
			)
			(layer "B.Fab")
		)
		(fp_line
			(start 0.12065 0.2794)
			(end 0.12065 0.3048)
			(stroke
				(width 0.1)
				(type default)
			)
			(layer "B.Fab")
		)
		(fp_line
			(start -0.120396 0.2794)
			(end 0.12065 0.2794)
			(stroke
				(width 0.1)
				(type default)
			)
			(layer "B.Fab")
		)
		(fp_line
			(start 0.67945 0.3048)
			(end 0.67945 -0.305054)
			(stroke
				(width 0.1)
				(type default)
			)
			(layer "B.Fab")
		)
		(fp_line
			(start 0.12065 0.3048)
			(end 0.67945 0.3048)
			(stroke
				(width 0.1)
				(type default)
			)
			(layer "B.Fab")
		)
		(fp_line
			(start -0.120396 0.3048)
			(end -0.120396 0.2794)
			(stroke
				(width 0.1)
				(type default)
			)
			(layer "B.Fab")
		)
		(fp_line
			(start -0.67945 0.3048)
			(end -0.120396 0.3048)
			(stroke
				(width 0.1)
				(type default)
			)
			(layer "B.Fab")
		)
		(pad "1" smd circle
			(at 0.40005 0 270)
			(size 0 0)
			(layers "B.Cu" "B.Mask" "B.Paste")
			(net "PVDD18_S5_P1")
		)
		(pad "2" smd circle
			(at -0.40005 0 270)
			(size 0 0)
			(layers "B.Cu" "B.Mask" "B.Paste")
			(net "JTAG_CPU1_TRST_N")
		)
	)
)
